# T6G (Grand Teton) — schematic netlist excerpt (pin names and nets, part order shuffled) for the footprints in the layout excerpt that follows; sources: Cadence DE-HDL packaged netlist, KiCad conversion of 04192023_DAF0TMB3IC0_F0TG_MB_C_brd_V02_OCP.brd

C124  Q_CAP  0.1UF 25V 10% X7R  pkg 0402  page 95 : A = P3V3_AUX ; B = GND
R286  Q_RES  0 5% CHIP  pkg 0402LF  page 81 : A = PWRGD_PVDDCR_CPU1_P1 ; B = FM_PWRGD_PVDDCR_CPU1_P1

(kicad_pcb
	(version 20260206)
	(generator "pcbnew")
	(generator_version "10.0")
	(general
		(thickness 1.6)
		(legacy_teardrops no)
	)
	(paper "A4")
	(title_block
		(title "04192023_DAF0TMB3IC0_F0TG_MB_C_brd_V02_OCP.brd")
		(comment 1 "Grand Teton / footprints 5891-5892 of 8354")
	)
	(layers
		(0 "F.Cu" signal "TOP")
		(4 "In1.Cu" signal "GND")
		(6 "In2.Cu" signal "IN1")
		(8 "In3.Cu" signal "GND1")
		(10 "In4.Cu" signal "IN2")
		(12 "In5.Cu" signal "GND2")
		(14 "In6.Cu" signal "IN3")
		(16 "In7.Cu" signal "GND3")
		(18 "In8.Cu" signal "VCC")
		(20 "In9.Cu" signal "VCC1")
		(22 "In10.Cu" signal "GND4")
		(24 "In11.Cu" signal "IN4")
		(26 "In12.Cu" signal "GND5")
		(28 "In13.Cu" signal "IN5")
		(30 "In14.Cu" signal "GND6")
		(32 "In15.Cu" signal "IN6")
		(34 "In16.Cu" signal "GND7")
		(2 "B.Cu" signal "BOTTOM")
		(9 "F.Adhes" user "F.Adhesive")
		(11 "B.Adhes" user "B.Adhesive")
		(13 "F.Paste" user "Package Geometry/Pastemask Top")
		(15 "B.Paste" user "Package Geometry/Pastemask Bottom")
		(5 "F.SilkS" user "Ref Des/Silkscreen Top")
		(7 "B.SilkS" user "Ref Des/Silkscreen Bottom")
		(1 "F.Mask" user "Board Geometry/Soldermask Top")
		(3 "B.Mask" user "Board Geometry/Soldermask Bottom")
		(17 "Dwgs.User" user "User.Drawings")
		(19 "Cmts.User" user "User.Comments")
		(21 "Eco1.User" user "User.Eco1")
		(23 "Eco2.User" user "User.Eco2")
		(25 "Edge.Cuts" user "Board Geometry/Outline")
		(27 "Margin" user)
		(31 "F.CrtYd" user "Package Geometry/Place Bound Top")
		(29 "B.CrtYd" user "Package Geometry/Place Bound Bottom")
		(35 "F.Fab" user "Ref Des/Assembly Top")
		(33 "B.Fab" user "Ref Des/Assembly Bottom")
	)
	(footprint ""
		(layer "B.Cu")
		(at 197.269608 -108.545376)
		(property "Reference" "R286"
			(at 0 0 0)
			(layer "B.SilkS")
			(hide yes)
			(effects
				(font
					(size 1.27 1.27)
				)
				(justify mirror)
			)
		)
		(property "Value" ""
			(at 0 0 0)
			(layer "B.Fab")
			(effects
				(font
					(size 1.27 1.27)
				)
				(justify mirror)
			)
		)
		(duplicate_pad_numbers_are_jumpers no)
		(fp_line
			(start -0.7874 -0.4064)
			(end -0.7874 0.4064)
			(stroke
				(width 0.1524)
				(type default)
			)
			(layer "B.SilkS")
		)
		(fp_line
			(start -0.7874 0.4064)
			(end 0.7874 0.4064)
			(stroke
				(width 0.1524)
				(type default)
			)
			(layer "B.SilkS")
		)
		(fp_line
			(start 0.7874 -0.4064)
			(end -0.7874 -0.4064)
			(stroke
				(width 0.1524)
				(type default)
			)
			(layer "B.SilkS")
		)
		(fp_line
			(start 0.7874 0.4064)
			(end 0.7874 -0.4064)
			(stroke
				(width 0.1524)
				(type default)
			)
			(layer "B.SilkS")
		)
		(fp_line
			(start -0.67945 -0.3048)
			(end -0.67945 0.3048)
			(stroke
				(width 0.1)
				(type default)
			)
			(layer "B.Fab")
		)
		(fp_line
			(start -0.67945 0.3048)
			(end -0.120396 0.3048)
			(stroke
				(width 0.1)
				(type default)
			)
			(layer "B.Fab")
		)
		(fp_line
			(start -0.12065 -0.3048)
			(end -0.67945 -0.3048)
			(stroke
				(width 0.1)
				(type default)
			)
			(layer "B.Fab")
		)
		(fp_line
			(start -0.12065 -0.2794)
			(end -0.12065 -0.3048)
			(stroke
				(width 0.1)
				(type default)
			)
			(layer "B.Fab")
		)
		(fp_line
			(start -0.120396 0.2794)
			(end 0.12065 0.2794)
			(stroke
				(width 0.1)
				(type default)
			)
			(layer "B.Fab")
		)
		(fp_line
			(start -0.120396 0.3048)
			(end -0.120396 0.2794)
			(stroke
				(width 0.1)
				(type default)
			)
			(layer "B.Fab")
		)
		(fp_line
			(start 0.12065 -0.305054)
			(end 0.12065 -0.2794)
			(stroke
				(width 0.1)
				(type default)
			)
			(layer "B.Fab")
		)
		(fp_line
			(start 0.12065 -0.2794)
			(end -0.12065 -0.2794)
			(stroke
				(width 0.1)
				(type default)
			)
			(layer "B.Fab")
		)
		(fp_line
			(start 0.12065 0.2794)
			(end 0.12065 0.3048)
			(stroke
				(width 0.1)
				(type default)
			)
			(layer "B.Fab")
		)
		(fp_line
			(start 0.12065 0.3048)
			(end 0.67945 0.3048)
			(stroke
				(width 0.1)
				(type default)
			)
			(layer "B.Fab")
		)
		(fp_line
			(start 0.67945 -0.305054)
			(end 0.12065 -0.305054)
			(stroke
				(width 0.1)
				(type default)
			)
			(layer "B.Fab")
		)
		(fp_line
			(start 0.67945 0.3048)
			(end 0.67945 -0.305054)
			(stroke
				(width 0.1)
				(type default)
			)
			(layer "B.Fab")
		)
		(pad "1" smd circle
			(at 0.40005 0 180)
			(size 0 0)
			(layers "B.Cu" "B.Mask" "B.Paste")
			(net "PWRGD_PVDDCR_CPU1_P1")
		)
		(pad "2" smd circle
			(at -0.40005 0 180)
			(size 0 0)
			(layers "B.Cu" "B.Mask" "B.Paste")
			(net "FM_PWRGD_PVDDCR_CPU1_P1")
		)
	)
	(footprint ""
		(layer "B.Cu")
		(at 430.80051 -193.99631)
		(property "Reference" "C124"
			(at 0 0 0)
			(layer "B.SilkS")
			(hide yes)
			(effects
				(font
					(size 1.27 1.27)
				)
				(justify mirror)
			)
		)
		(property "Value" ""
			(at 0 0 0)
			(layer "B.Fab")
			(effects
				(font
					(size 1.27 1.27)
				)
				(justify mirror)
			)
		)
		(duplicate_pad_numbers_are_jumpers no)
		(fp_line
			(start -0.7874 -0.4064)
			(end -0.7874 0.4064)
			(stroke
				(width 0.1524)
				(type default)
			)
			(layer "B.SilkS")
		)
		(fp_line
			(start -0.7874 0.4064)
			(end 0.7874 0.4064)
			(stroke
				(width 0.1524)
				(type default)
			)
			(layer "B.SilkS")
		)
		(fp_line
			(start 0.7874 -0.4064)
			(end -0.7874 -0.4064)
			(stroke
				(width 0.1524)
				(type default)
			)
			(layer "B.SilkS")
		)
		(fp_line
			(start 0.7874 0.4064)
			(end 0.7874 -0.4064)
			(stroke
				(width 0.1524)
				(type default)
			)
			(layer "B.SilkS")
		)
		(fp_line
			(start -0.67945 -0.3048)
			(end -0.67945 0.3048)
			(stroke
				(width 0.1)
				(type default)
			)
			(layer "B.Fab")
		)
		(fp_line
			(start -0.67945 0.3048)
			(end -0.120396 0.3048)
			(stroke
				(width 0.1)
				(type default)
			)
			(layer "B.Fab")
		)
		(fp_line
			(start -0.12065 -0.3048)
			(end -0.67945 -0.3048)
			(stroke
				(width 0.1)
				(type default)
			)
			(layer "B.Fab")
		)
		(fp_line
			(start -0.12065 -0.2794)
			(end -0.12065 -0.3048)
			(stroke
				(width 0.1)
				(type default)
			)
			(layer "B.Fab")
		)
		(fp_line
			(start -0.120396 0.2794)
			(end 0.12065 0.2794)
			(stroke
				(width 0.1)
				(type default)
			)
			(layer "B.Fab")
		)
		(fp_line
			(start -0.120396 0.3048)
			(end -0.120396 0.2794)
			(stroke
				(width 0.1)
				(type default)
			)
			(layer "B.Fab")
		)
		(fp_line
			(start 0.12065 -0.305054)
			(end 0.12065 -0.2794)
			(stroke
				(width 0.1)
				(type default)
			)
			(layer "B.Fab")
		)
		(fp_line
			(start 0.12065 -0.2794)
			(end -0.12065 -0.2794)
			(stroke
				(width 0.1)
				(type default)
			)
			(layer "B.Fab")
		)
		(fp_line
			(start 0.12065 0.2794)
			(end 0.12065 0.3048)
			(stroke
				(width 0.1)
				(type default)
			)
			(layer "B.Fab")
		)
		(fp_line
			(start 0.12065 0.3048)
			(end 0.67945 0.3048)
			(stroke
				(width 0.1)
				(type default)
			)
			(layer "B.Fab")
		)
		(fp_line
			(start 0.67945 -0.305054)
			(end 0.12065 -0.305054)
			(stroke
				(width 0.1)
				(type default)
			)
			(layer "B.Fab")
		)
		(fp_line
			(start 0.67945 0.3048)
			(end 0.67945 -0.305054)
			(stroke
				(width 0.1)
				(type default)
			)
			(layer "B.Fab")
		)
		(pad "1" smd circle
			(at 0.40005 0 180)
			(size 0 0)
			(layers "B.Cu" "B.Mask" "B.Paste")
			(net "P3V3_AUX")
		)
		(pad "2" smd circle
			(at -0.40005 0 180)
			(size 0 0)
			(layers "B.Cu" "B.Mask" "B.Paste")
			(net "GND")
		)
	)
)
